(kicad_pcb
	(version 20260206)
	(generator "pcbnew")
	(generator_version "10.0")
	(general
		(thickness 1.6)
		(legacy_teardrops no)
	)
	(paper "A4")
	(title_block
		(title "04192023_DAF0TMB3IC0_F0TG_MB_C_brd_V02_OCP.brd")
		(comment 1 "Grand Teton / footprints 4279-4285 of 8354")
	)
	(layers
		(0 "F.Cu" signal "TOP")
		(4 "In1.Cu" signal "GND")
		(6 "In2.Cu" signal "IN1")
		(8 "In3.Cu" signal "GND1")
		(10 "In4.Cu" signal "IN2")
		(12 "In5.Cu" signal "GND2")
		(14 "In6.Cu" signal "IN3")
		(16 "In7.Cu" signal "GND3")
		(18 "In8.Cu" signal "VCC")
		(20 "In9.Cu" signal "VCC1")
		(22 "In10.Cu" signal "GND4")
		(24 "In11.Cu" signal "IN4")
		(26 "In12.Cu" signal "GND5")
		(28 "In13.Cu" signal "IN5")
		(30 "In14.Cu" signal "GND6")
		(32 "In15.Cu" signal "IN6")
		(34 "In16.Cu" signal "GND7")
		(2 "B.Cu" signal "BOTTOM")
		(9 "F.Adhes" user "F.Adhesive")
		(11 "B.Adhes" user "B.Adhesive")
		(13 "F.Paste" user "Package Geometry/Pastemask Top")
		(15 "B.Paste" user "Package Geometry/Pastemask Bottom")
		(5 "F.SilkS" user "Ref Des/Silkscreen Top")
		(7 "B.SilkS" user "Ref Des/Silkscreen Bottom")
		(1 "F.Mask" user "Board Geometry/Soldermask Top")
		(3 "B.Mask" user "Board Geometry/Soldermask Bottom")
		(17 "Dwgs.User" user "User.Drawings")
		(19 "Cmts.User" user "User.Comments")
		(21 "Eco1.User" user "User.Eco1")
		(23 "Eco2.User" user "User.Eco2")
		(25 "Edge.Cuts" user "Board Geometry/Outline")
		(27 "Margin" user)
		(31 "F.CrtYd" user "Package Geometry/Place Bound Top")
		(29 "B.CrtYd" user "Package Geometry/Place Bound Bottom")
		(35 "F.Fab" user "Ref Des/Assembly Top")
		(33 "B.Fab" user "Ref Des/Assembly Bottom")
	)
	(footprint ""
		(layer "F.Cu")
		(at 323.624194 -38.10762)
		(property "Reference" "R4568"
			(at 0 0 0)
			(layer "F.SilkS")
			(hide yes)
			(effects
				(font
					(size 1.27 1.27)
				)
			)
		)
		(property "Value" ""
			(at 0 0 0)
			(layer "F.Fab")
			(effects
				(font
					(size 1.27 1.27)
				)
			)
		)
		(duplicate_pad_numbers_are_jumpers no)
		(fp_line
			(start -0.7874 -0.4064)
			(end 0.7874 -0.4064)
			(stroke
				(width 0.1524)
				(type default)
			)
			(layer "F.SilkS")
		)
		(fp_line
			(start -0.7874 0.4064)
			(end -0.7874 -0.4064)
			(stroke
				(width 0.1524)
				(type default)
			)
			(layer "F.SilkS")
		)
		(fp_line
			(start 0.7874 -0.4064)
			(end 0.7874 0.4064)
			(stroke
				(width 0.1524)
				(type default)
			)
			(layer "F.SilkS")
		)
		(fp_line
			(start 0.7874 0.4064)
			(end -0.7874 0.4064)
			(stroke
				(width 0.1524)
				(type default)
			)
			(layer "F.SilkS")
		)
		(fp_line
			(start -0.67945 -0.305054)
			(end -0.12065 -0.305054)
			(stroke
				(width 0.1)
				(type default)
			)
			(layer "F.Fab")
		)
		(fp_line
			(start -0.67945 0.3048)
			(end -0.67945 -0.305054)
			(stroke
				(width 0.1)
				(type default)
			)
			(layer "F.Fab")
		)
		(fp_line
			(start -0.12065 -0.305054)
			(end -0.12065 -0.2794)
			(stroke
				(width 0.1)
				(type default)
			)
			(layer "F.Fab")
		)
		(fp_line
			(start -0.12065 -0.2794)
			(end 0.12065 -0.2794)
			(stroke
				(width 0.1)
				(type default)
			)
			(layer "F.Fab")
		)
		(fp_line
			(start -0.12065 0.2794)
			(end -0.12065 0.3048)
			(stroke
				(width 0.1)
				(type default)
			)
			(layer "F.Fab")
		)
		(fp_line
			(start -0.12065 0.3048)
			(end -0.67945 0.3048)
			(stroke
				(width 0.1)
				(type default)
			)
			(layer "F.Fab")
		)
		(fp_line
			(start 0.120396 0.2794)
			(end -0.12065 0.2794)
			(stroke
				(width 0.1)
				(type default)
			)
			(layer "F.Fab")
		)
		(fp_line
			(start 0.120396 0.3048)
			(end 0.120396 0.2794)
			(stroke
				(width 0.1)
				(type default)
			)
			(layer "F.Fab")
		)
		(fp_line
			(start 0.12065 -0.3048)
			(end 0.67945 -0.3048)
			(stroke
				(width 0.1)
				(type default)
			)
			(layer "F.Fab")
		)
		(fp_line
			(start 0.12065 -0.2794)
			(end 0.12065 -0.3048)
			(stroke
				(width 0.1)
				(type default)
			)
			(layer "F.Fab")
		)
		(fp_line
			(start 0.67945 -0.3048)
			(end 0.67945 0.3048)
			(stroke
				(width 0.1)
				(type default)
			)
			(layer "F.Fab")
		)
		(fp_line
			(start 0.67945 0.3048)
			(end 0.120396 0.3048)
			(stroke
				(width 0.1)
				(type default)
			)
			(layer "F.Fab")
		)
		(pad "1" smd circle
			(at -0.40005 0)
			(size 0 0)
			(layers "F.Cu" "F.Mask" "F.Paste")
			(net "P1V581_PDB_ADC")
		)
		(pad "2" smd circle
			(at 0.40005 0)
			(size 0 0)
			(layers "F.Cu" "F.Mask" "F.Paste")
			(net "GND")
		)
	)
	(footprint ""
		(layer "F.Cu")
		(at 192.151 -129.377948 90)
		(property "Reference" "R277"
			(at 0 0 90)
			(layer "F.SilkS")
			(hide yes)
			(effects
				(font
					(size 1.27 1.27)
				)
			)
		)
		(property "Value" ""
			(at 0 0 90)
			(layer "F.Fab")
			(effects
				(font
					(size 1.27 1.27)
				)
			)
		)
		(duplicate_pad_numbers_are_jumpers no)
		(fp_line
			(start 0.7874 -0.4064)
			(end 0.7874 0.4064)
			(stroke
				(width 0.1524)
				(type default)
			)
			(layer "F.SilkS")
		)
		(fp_line
			(start -0.7874 -0.4064)
			(end 0.7874 -0.4064)
			(stroke
				(width 0.1524)
				(type default)
			)
			(layer "F.SilkS")
		)
		(fp_line
			(start 0.7874 0.4064)
			(end -0.7874 0.4064)
			(stroke
				(width 0.1524)
				(type default)
			)
			(layer "F.SilkS")
		)
		(fp_line
			(start -0.7874 0.4064)
			(end -0.7874 -0.4064)
			(stroke
				(width 0.1524)
				(type default)
			)
			(layer "F.SilkS")
		)
		(fp_line
			(start -0.12065 -0.305054)
			(end -0.12065 -0.2794)
			(stroke
				(width 0.1)
				(type default)
			)
			(layer "F.Fab")
		)
		(fp_line
			(start -0.67945 -0.305054)
			(end -0.12065 -0.305054)
			(stroke
				(width 0.1)
				(type default)
			)
			(layer "F.Fab")
		)
		(fp_line
			(start 0.67945 -0.3048)
			(end 0.67945 0.3048)
			(stroke
				(width 0.1)
				(type default)
			)
			(layer "F.Fab")
		)
		(fp_line
			(start 0.12065 -0.3048)
			(end 0.67945 -0.3048)
			(stroke
				(width 0.1)
				(type default)
			)
			(layer "F.Fab")
		)
		(fp_line
			(start 0.12065 -0.2794)
			(end 0.12065 -0.3048)
			(stroke
				(width 0.1)
				(type default)
			)
			(layer "F.Fab")
		)
		(fp_line
			(start -0.12065 -0.2794)
			(end 0.12065 -0.2794)
			(stroke
				(width 0.1)
				(type default)
			)
			(layer "F.Fab")
		)
		(fp_line
			(start 0.120396 0.2794)
			(end -0.12065 0.2794)
			(stroke
				(width 0.1)
				(type default)
			)
			(layer "F.Fab")
		)
		(fp_line
			(start -0.12065 0.2794)
			(end -0.12065 0.3048)
			(stroke
				(width 0.1)
				(type default)
			)
			(layer "F.Fab")
		)
		(fp_line
			(start 0.67945 0.3048)
			(end 0.120396 0.3048)
			(stroke
				(width 0.1)
				(type default)
			)
			(layer "F.Fab")
		)
		(fp_line
			(start 0.120396 0.3048)
			(end 0.120396 0.2794)
			(stroke
				(width 0.1)
				(type default)
			)
			(layer "F.Fab")
		)
		(fp_line
			(start -0.12065 0.3048)
			(end -0.67945 0.3048)
			(stroke
				(width 0.1)
				(type default)
			)
			(layer "F.Fab")
		)
		(fp_line
			(start -0.67945 0.3048)
			(end -0.67945 -0.305054)
			(stroke
				(width 0.1)
				(type default)
			)
			(layer "F.Fab")
		)
		(pad "1" smd circle
			(at -0.40005 0 90)
			(size 0 0)
			(layers "F.Cu" "F.Mask" "F.Paste")
			(net "FM_CPU1_NMI_SYNC_FLOOD_N")
		)
		(pad "2" smd circle
			(at 0.40005 0 90)
			(size 0 0)
			(layers "F.Cu" "F.Mask" "F.Paste")
			(net "CPU1_NMI_SYNC_FLOOD_N")
		)
	)
	(footprint ""
		(layer "F.Cu")
		(at 200.057258 -77.06614 180)
		(property "Reference" "R72"
			(at 0 0 180)
			(layer "F.SilkS")
			(hide yes)
			(effects
				(font
					(size 1.27 1.27)
				)
			)
		)
		(property "Value" ""
			(at 0 0 180)
			(layer "F.Fab")
			(effects
				(font
					(size 1.27 1.27)
				)
			)
		)
		(duplicate_pad_numbers_are_jumpers no)
		(fp_line
			(start 0.7874 0.4064)
			(end -0.7874 0.4064)
			(stroke
				(width 0.1524)
				(type default)
			)
			(layer "F.SilkS")
		)
		(fp_line
			(start 0.7874 -0.4064)
			(end 0.7874 0.4064)
			(stroke
				(width 0.1524)
				(type default)
			)
			(layer "F.SilkS")
		)
		(fp_line
			(start -0.7874 0.4064)
			(end -0.7874 -0.4064)
			(stroke
				(width 0.1524)
				(type default)
			)
			(layer "F.SilkS")
		)
		(fp_line
			(start -0.7874 -0.4064)
			(end 0.7874 -0.4064)
			(stroke
				(width 0.1524)
				(type default)
			)
			(layer "F.SilkS")
		)
		(fp_line
			(start 0.67945 0.3048)
			(end 0.120396 0.3048)
			(stroke
				(width 0.1)
				(type default)
			)
			(layer "F.Fab")
		)
		(fp_line
			(start 0.67945 -0.3048)
			(end 0.67945 0.3048)
			(stroke
				(width 0.1)
				(type default)
			)
			(layer "F.Fab")
		)
		(fp_line
			(start 0.12065 -0.2794)
			(end 0.12065 -0.3048)
			(stroke
				(width 0.1)
				(type default)
			)
			(layer "F.Fab")
		)
		(fp_line
			(start 0.12065 -0.3048)
			(end 0.67945 -0.3048)
			(stroke
				(width 0.1)
				(type default)
			)
			(layer "F.Fab")
		)
		(fp_line
			(start 0.120396 0.3048)
			(end 0.120396 0.2794)
			(stroke
				(width 0.1)
				(type default)
			)
			(layer "F.Fab")
		)
		(fp_line
			(start 0.120396 0.2794)
			(end -0.12065 0.2794)
			(stroke
				(width 0.1)
				(type default)
			)
			(layer "F.Fab")
		)
		(fp_line
			(start -0.12065 0.3048)
			(end -0.67945 0.3048)
			(stroke
				(width 0.1)
				(type default)
			)
			(layer "F.Fab")
		)
		(fp_line
			(start -0.12065 0.2794)
			(end -0.12065 0.3048)
			(stroke
				(width 0.1)
				(type default)
			)
			(layer "F.Fab")
		)
		(fp_line
			(start -0.12065 -0.2794)
			(end 0.12065 -0.2794)
			(stroke
				(width 0.1)
				(type default)
			)
			(layer "F.Fab")
		)
		(fp_line
			(start -0.12065 -0.305054)
			(end -0.12065 -0.2794)
			(stroke
				(width 0.1)
				(type default)
			)
			(layer "F.Fab")
		)
		(fp_line
			(start -0.67945 0.3048)
			(end -0.67945 -0.305054)
			(stroke
				(width 0.1)
				(type default)
			)
			(layer "F.Fab")
		)
		(fp_line
			(start -0.67945 -0.305054)
			(end -0.12065 -0.305054)
			(stroke
				(width 0.1)
				(type default)
			)
			(layer "F.Fab")
		)
		(pad "1" smd circle
			(at -0.40005 0 180)
			(size 0 0)
			(layers "F.Cu" "F.Mask" "F.Paste")
			(net "NCSI_BMC_RXD0_R")
		)
		(pad "2" smd circle
			(at 0.40005 0 180)
			(size 0 0)
			(layers "F.Cu" "F.Mask" "F.Paste")
			(net "RMII_OCP_BMC_RXD_0")
		)
	)
	(footprint ""
		(layer "F.Cu")
		(at 41.5544 -389.0264)
		(property "Reference" "R6721"
			(at 0 0 0)
			(layer "F.SilkS")
			(hide yes)
			(effects
				(font
					(size 1.27 1.27)
				)
			)
		)
		(property "Value" ""
			(at 0 0 0)
			(layer "F.Fab")
			(effects
				(font
					(size 1.27 1.27)
				)
			)
		)
		(duplicate_pad_numbers_are_jumpers no)
		(fp_line
			(start -0.32512 -0.175006)
			(end 0.32512 -0.175006)
			(stroke
				(width 0.1)
				(type default)
			)
			(layer "F.Fab")
		)
		(fp_line
			(start -0.32512 0.175006)
			(end -0.32512 -0.175006)
			(stroke
				(width 0.1)
				(type default)
			)
			(layer "F.Fab")
		)
		(fp_line
			(start 0.32512 -0.175006)
			(end 0.32512 0.175006)
			(stroke
				(width 0.1)
				(type default)
			)
			(layer "F.Fab")
		)
		(fp_line
			(start 0.32512 0.175006)
			(end -0.32512 0.175006)
			(stroke
				(width 0.1)
				(type default)
			)
			(layer "F.Fab")
		)
		(pad "1" smd rect
			(at -0.2667 0)
			(size 0.3048 0.381)
			(layers "F.Cu" "F.Mask" "F.Paste")
			(net "RST_RT_CPU1_P0_RESET_R_N")
		)
		(pad "2" smd rect
			(at 0.2667 0 180)
			(size 0.3048 0.381)
			(layers "F.Cu" "F.Mask" "F.Paste")
			(net "GND")
		)
	)
	(footprint ""
		(layer "F.Cu")
		(at 255.780794 -140.118846 -90)
		(property "Reference" "R128"
			(at 0 0 270)
			(layer "F.SilkS")
			(hide yes)
			(effects
				(font
					(size 1.27 1.27)
				)
			)
		)
		(property "Value" ""
			(at 0 0 270)
			(layer "F.Fab")
			(effects
				(font
					(size 1.27 1.27)
				)
			)
		)
		(duplicate_pad_numbers_are_jumpers no)
		(fp_line
			(start -0.7874 0.4064)
			(end -0.7874 -0.4064)
			(stroke
				(width 0.1524)
				(type default)
			)
			(layer "F.SilkS")
		)
		(fp_line
			(start 0.7874 0.4064)
			(end -0.7874 0.4064)
			(stroke
				(width 0.1524)
				(type default)
			)
			(layer "F.SilkS")
		)
		(fp_line
			(start -0.7874 -0.4064)
			(end 0.7874 -0.4064)
			(stroke
				(width 0.1524)
				(type default)
			)
			(layer "F.SilkS")
		)
		(fp_line
			(start 0.7874 -0.4064)
			(end 0.7874 0.4064)
			(stroke
				(width 0.1524)
				(type default)
			)
			(layer "F.SilkS")
		)
		(fp_line
			(start -0.67945 0.3048)
			(end -0.67945 -0.305054)
			(stroke
				(width 0.1)
				(type default)
			)
			(layer "F.Fab")
		)
		(fp_line
			(start -0.12065 0.3048)
			(end -0.67945 0.3048)
			(stroke
				(width 0.1)
				(type default)
			)
			(layer "F.Fab")
		)
		(fp_line
			(start 0.120396 0.3048)
			(end 0.120396 0.2794)
			(stroke
				(width 0.1)
				(type default)
			)
			(layer "F.Fab")
		)
		(fp_line
			(start 0.67945 0.3048)
			(end 0.120396 0.3048)
			(stroke
				(width 0.1)
				(type default)
			)
			(layer "F.Fab")
		)
		(fp_line
			(start -0.12065 0.2794)
			(end -0.12065 0.3048)
			(stroke
				(width 0.1)
				(type default)
			)
			(layer "F.Fab")
		)
		(fp_line
			(start 0.120396 0.2794)
			(end -0.12065 0.2794)
			(stroke
				(width 0.1)
				(type default)
			)
			(layer "F.Fab")
		)
		(fp_line
			(start -0.12065 -0.2794)
			(end 0.12065 -0.2794)
			(stroke
				(width 0.1)
				(type default)
			)
			(layer "F.Fab")
		)
		(fp_line
			(start 0.12065 -0.2794)
			(end 0.12065 -0.3048)
			(stroke
				(width 0.1)
				(type default)
			)
			(layer "F.Fab")
		)
		(fp_line
			(start 0.12065 -0.3048)
			(end 0.67945 -0.3048)
			(stroke
				(width 0.1)
				(type default)
			)
			(layer "F.Fab")
		)
		(fp_line
			(start 0.67945 -0.3048)
			(end 0.67945 0.3048)
			(stroke
				(width 0.1)
				(type default)
			)
			(layer "F.Fab")
		)
		(fp_line
			(start -0.67945 -0.305054)
			(end -0.12065 -0.305054)
			(stroke
				(width 0.1)
				(type default)
			)
			(layer "F.Fab")
		)
		(fp_line
			(start -0.12065 -0.305054)
			(end -0.12065 -0.2794)
			(stroke
				(width 0.1)
				(type default)
			)
			(layer "F.Fab")
		)
		(pad "1" smd circle
			(at -0.40005 0 270)
			(size 0 0)
			(layers "F.Cu" "F.Mask" "F.Paste")
			(net "P3V3_AUX")
		)
		(pad "2" smd circle
			(at 0.40005 0 270)
			(size 0 0)
			(layers "F.Cu" "F.Mask" "F.Paste")
			(net "SPI_CPU0_LVC3_SCM_D2")
		)
	)
	(footprint ""
		(layer "F.Cu")
		(at 163.715446 -419.0492 90)
		(property "Reference" "R693"
			(at 0 0 90)
			(layer "F.SilkS")
			(hide yes)
			(effects
				(font
					(size 1.27 1.27)
				)
			)
		)
		(property "Value" ""
			(at 0 0 90)
			(layer "F.Fab")
			(effects
				(font
					(size 1.27 1.27)
				)
			)
		)
		(duplicate_pad_numbers_are_jumpers no)
		(fp_line
			(start 0.32512 -0.175006)
			(end 0.32512 0.175006)
			(stroke
				(width 0.1)
				(type default)
			)
			(layer "F.Fab")
		)
		(fp_line
			(start -0.32512 -0.175006)
			(end 0.32512 -0.175006)
			(stroke
				(width 0.1)
				(type default)
			)
			(layer "F.Fab")
		)
		(fp_line
			(start 0.32512 0.175006)
			(end -0.32512 0.175006)
			(stroke
				(width 0.1)
				(type default)
			)
			(layer "F.Fab")
		)
		(fp_line
			(start -0.32512 0.175006)
			(end -0.32512 -0.175006)
			(stroke
				(width 0.1)
				(type default)
			)
			(layer "F.Fab")
		)
		(pad "1" smd rect
			(at -0.2667 0 90)
			(size 0.3048 0.381)
			(layers "F.Cu" "F.Mask" "F.Paste")
			(net "SMB_RT_CPU1_P2_ROM_R_SCL")
		)
		(pad "2" smd rect
			(at 0.2667 0 270)
			(size 0.3048 0.381)
			(layers "F.Cu" "F.Mask" "F.Paste")
			(net "SMB_RT_CPU1_P2_ROM_SCL")
		)
	)
	(footprint ""
		(layer "F.Cu")
		(at 438.256172 -32.173418 90)
		(property "Reference" "PR3837"
			(at 0 0 90)
			(layer "F.SilkS")
			(hide yes)
			(effects
				(font
					(size 1.27 1.27)
				)
			)
		)
		(property "Value" ""
			(at 0 0 90)
			(layer "F.Fab")
			(effects
				(font
					(size 1.27 1.27)
				)
			)
		)
		(duplicate_pad_numbers_are_jumpers no)
		(fp_line
			(start 0.7874 -0.4064)
			(end 0.7874 0.4064)
			(stroke
				(width 0.1524)
				(type default)
			)
			(layer "F.SilkS")
		)
		(fp_line
			(start -0.7874 -0.4064)
			(end 0.7874 -0.4064)
			(stroke
				(width 0.1524)
				(type default)
			)
			(layer "F.SilkS")
		)
		(fp_line
			(start 0.7874 0.4064)
			(end -0.7874 0.4064)
			(stroke
				(width 0.1524)
				(type default)
			)
			(layer "F.SilkS")
		)
		(fp_line
			(start -0.7874 0.4064)
			(end -0.7874 -0.4064)
			(stroke
				(width 0.1524)
				(type default)
			)
			(layer "F.SilkS")
		)
		(fp_line
			(start -0.12065 -0.305054)
			(end -0.12065 -0.2794)
			(stroke
				(width 0.1)
				(type default)
			)
			(layer "F.Fab")
		)
		(fp_line
			(start -0.67945 -0.305054)
			(end -0.12065 -0.305054)
			(stroke
				(width 0.1)
				(type default)
			)
			(layer "F.Fab")
		)
		(fp_line
			(start 0.67945 -0.3048)
			(end 0.67945 0.3048)
			(stroke
				(width 0.1)
				(type default)
			)
			(layer "F.Fab")
		)
		(fp_line
			(start 0.12065 -0.3048)
			(end 0.67945 -0.3048)
			(stroke
				(width 0.1)
				(type default)
			)
			(layer "F.Fab")
		)
		(fp_line
			(start 0.12065 -0.2794)
			(end 0.12065 -0.3048)
			(stroke
				(width 0.1)
				(type default)
			)
			(layer "F.Fab")
		)
		(fp_line
			(start -0.12065 -0.2794)
			(end 0.12065 -0.2794)
			(stroke
				(width 0.1)
				(type default)
			)
			(layer "F.Fab")
		)
		(fp_line
			(start 0.120396 0.2794)
			(end -0.12065 0.2794)
			(stroke
				(width 0.1)
				(type default)
			)
			(layer "F.Fab")
		)
		(fp_line
			(start -0.12065 0.2794)
			(end -0.12065 0.3048)
			(stroke
				(width 0.1)
				(type default)
			)
			(layer "F.Fab")
		)
		(fp_line
			(start 0.67945 0.3048)
			(end 0.120396 0.3048)
			(stroke
				(width 0.1)
				(type default)
			)
			(layer "F.Fab")
		)
		(fp_line
			(start 0.120396 0.3048)
			(end 0.120396 0.2794)
			(stroke
				(width 0.1)
				(type default)
			)
			(layer "F.Fab")
		)
		(fp_line
			(start -0.12065 0.3048)
			(end -0.67945 0.3048)
			(stroke
				(width 0.1)
				(type default)
			)
			(layer "F.Fab")
		)
		(fp_line
			(start -0.67945 0.3048)
			(end -0.67945 -0.305054)
			(stroke
				(width 0.1)
				(type default)
			)
			(layer "F.Fab")
		)
		(pad "1" smd circle
			(at -0.40005 0 90)
			(size 0 0)
			(layers "F.Cu" "F.Mask" "F.Paste")
			(net "P12V_OCP_IMON_1")
		)
		(pad "2" smd circle
			(at 0.40005 0 90)
			(size 0 0)
			(layers "F.Cu" "F.Mask" "F.Paste")
			(net "GND")
		)
	)
)
